(kicad_pcb
	(version 20260206)
	(generator "pcbnew")
	(generator_version "10.0")
	(general
		(thickness 1.6)
		(legacy_teardrops no)
	)
	(paper "A4")
	(title_block
		(title "Wiwynn_Tioga_Pass_MB.brd")
		(comment 1 "Tioga Pass / footprints 3342-3349 of 4770")
	)
	(layers
		(0 "F.Cu" signal "TOP")
		(4 "In1.Cu" signal "L2GND")
		(6 "In2.Cu" signal "L3")
		(8 "In3.Cu" signal "L4GND")
		(10 "In4.Cu" signal "L5")
		(12 "In5.Cu" signal "L6GND")
		(14 "In6.Cu" signal "L7VCC")
		(16 "In7.Cu" signal "L8VCC")
		(18 "In8.Cu" signal "L9GND")
		(20 "In9.Cu" signal "L10")
		(22 "In10.Cu" signal "L11GND")
		(24 "In11.Cu" signal "L12")
		(26 "In12.Cu" signal "L13GND")
		(2 "B.Cu" signal "BOTTOM")
		(9 "F.Adhes" user "F.Adhesive")
		(11 "B.Adhes" user "B.Adhesive")
		(13 "F.Paste" user "Package Geometry/Pastemask Top")
		(15 "B.Paste" user "Package Geometry/Pastemask Bottom")
		(5 "F.SilkS" user "Ref Des/Silkscreen Top")
		(7 "B.SilkS" user "Ref Des/Silkscreen Bottom")
		(1 "F.Mask" user "Board Geometry/Soldermask Top")
		(3 "B.Mask" user "Board Geometry/Soldermask Bottom")
		(17 "Dwgs.User" user "User.Drawings")
		(19 "Cmts.User" user "User.Comments")
		(21 "Eco1.User" user "User.Eco1")
		(23 "Eco2.User" user "User.Eco2")
		(25 "Edge.Cuts" user "Board Geometry/Outline")
		(27 "Margin" user)
		(31 "F.CrtYd" user "Package Geometry/Place Bound Top")
		(29 "B.CrtYd" user "Package Geometry/Place Bound Bottom")
		(35 "F.Fab" user "Ref Des/Assembly Top")
		(33 "B.Fab" user "Ref Des/Assembly Bottom")
	)
	(footprint ""
		(layer "B.Cu")
		(at 13.84046 -106.59618 90)
		(property "Reference" "C9N4"
			(at 0 0 90)
			(layer "B.SilkS")
			(hide yes)
			(effects
				(font
					(size 1.27 1.27)
				)
				(justify mirror)
			)
		)
		(property "Value" ""
			(at 0 0 90)
			(layer "B.Fab")
			(effects
				(font
					(size 1.27 1.27)
				)
				(justify mirror)
			)
		)
		(duplicate_pad_numbers_are_jumpers no)
		(fp_poly
			(pts
				(xy -0.3048 -0.1016) (xy -0.3048 0.9906) (xy 0.3048 0.9906) (xy 0.3048 -0.1016)
			)
			(stroke
				(width 0)
				(type default)
			)
			(fill no)
			(layer "B.CrtYd")
		)
		(fp_line
			(start 0.3048 -0.1016)
			(end 0.3048 0.9906)
			(stroke
				(width 0.1)
				(type default)
			)
			(layer "B.Fab")
		)
		(fp_line
			(start -0.3048 -0.1016)
			(end 0.3048 -0.1016)
			(stroke
				(width 0.1)
				(type default)
			)
			(layer "B.Fab")
		)
		(fp_line
			(start 0.3048 0.9906)
			(end -0.3048 0.9906)
			(stroke
				(width 0.1)
				(type default)
			)
			(layer "B.Fab")
		)
		(fp_line
			(start -0.3048 0.9906)
			(end -0.3048 -0.1016)
			(stroke
				(width 0.1)
				(type default)
			)
			(layer "B.Fab")
		)
		(pad "1" smd rect
			(at 0 0 270)
			(size 0.508 0.508)
			(layers "B.Cu" "B.Mask" "B.Paste")
			(net "P3E_CPU1_PE3_MP_C_TXP<11>")
		)
		(pad "2" smd rect
			(at 0 0.889 270)
			(size 0.508 0.508)
			(layers "B.Cu" "B.Mask" "B.Paste")
			(net "P3E_CPU1_PE3_MP_TXP<11>")
		)
		(zone
			(layer "B.Cu")
			(hatch none 0.5)
			(connect_pads
				(clearance 0)
			)
			(min_thickness 0.25)
			(keepout
				(tracks allowed)
				(vias not_allowed)
				(pads allowed)
				(copperpour not_allowed)
				(footprints allowed)
			)
			(placement
				(enabled no)
				(sheetname "")
			)
			(fill
				(thermal_gap 0.5)
				(thermal_bridge_width 0.5)
				(island_removal_mode 0)
			)
			(polygon
				(pts
					(xy 14.09446 -106.85018) (xy 14.09446 -106.34218) (xy 14.47546 -106.34218) (xy 14.47546 -106.85018)
				)
			)
		)
		(zone
			(layer "B.Cu")
			(hatch none 0.5)
			(connect_pads
				(clearance 0)
			)
			(min_thickness 0.25)
			(keepout
				(tracks not_allowed)
				(vias allowed)
				(pads allowed)
				(copperpour not_allowed)
				(footprints allowed)
			)
			(placement
				(enabled no)
				(sheetname "")
			)
			(fill
				(thermal_gap 0.5)
				(thermal_bridge_width 0.5)
				(island_removal_mode 0)
			)
			(polygon
				(pts
					(xy 14.47546 -106.85018) (xy 14.47546 -106.34218) (xy 14.09446 -106.34218) (xy 14.09446 -106.85018)
				)
			)
		)
	)
	(footprint ""
		(layer "B.Cu")
		(at 458.0001 -41.51376 -90)
		(property "Reference" "C9W16"
			(at -0.97536 0.76708 0)
			(unlocked yes)
			(layer "B.SilkS")
			(effects
				(font
					(size 0.4064 0.254)
					(thickness 0.1524)
				)
				(justify mirror)
			)
		)
		(property "Value" ""
			(at 0 0 90)
			(layer "B.Fab")
			(effects
				(font
					(size 1.27 1.27)
				)
				(justify mirror)
			)
		)
		(duplicate_pad_numbers_are_jumpers no)
		(fp_poly
			(pts
				(xy 0.4953 -0.2032) (xy -0.4953 -0.2032) (xy -0.4953 1.6002) (xy 0.4953 1.6002)
			)
			(stroke
				(width 0)
				(type default)
			)
			(fill no)
			(layer "B.CrtYd")
		)
		(fp_line
			(start -0.4953 1.6002)
			(end 0.4953 1.6002)
			(stroke
				(width 0.1)
				(type default)
			)
			(layer "B.Fab")
		)
		(fp_line
			(start 0.4953 1.6002)
			(end 0.4953 -0.2032)
			(stroke
				(width 0.1)
				(type default)
			)
			(layer "B.Fab")
		)
		(fp_line
			(start -0.4953 -0.2032)
			(end -0.4953 1.6002)
			(stroke
				(width 0.1)
				(type default)
			)
			(layer "B.Fab")
		)
		(fp_line
			(start 0.4953 -0.2032)
			(end -0.4953 -0.2032)
			(stroke
				(width 0.1)
				(type default)
			)
			(layer "B.Fab")
		)
		(pad "1" smd rect
			(at 0 0 90)
			(size 0.762 0.889)
			(layers "B.Cu" "B.Mask" "B.Paste")
			(net "P1V15_AUX_BMC")
		)
		(pad "2" smd rect
			(at 0 1.397 90)
			(size 0.762 0.889)
			(layers "B.Cu" "B.Mask" "B.Paste")
			(net "GND")
		)
		(zone
			(layer "B.Cu")
			(hatch none 0.5)
			(connect_pads
				(clearance 0)
			)
			(min_thickness 0.25)
			(keepout
				(tracks not_allowed)
				(vias allowed)
				(pads allowed)
				(copperpour not_allowed)
				(footprints allowed)
			)
			(placement
				(enabled no)
				(sheetname "")
			)
			(fill
				(thermal_gap 0.5)
				(thermal_bridge_width 0.5)
				(island_removal_mode 0)
			)
			(polygon
				(pts
					(xy 457.5556 -41.13276) (xy 457.5556 -41.89476) (xy 457.0476 -41.89476) (xy 457.0476 -41.13276)
				)
			)
		)
	)
	(footprint ""
		(layer "B.Cu")
		(at 154.023568 -135.376412 -90)
		(property "Reference" "C7M4"
			(at 0 0 90)
			(layer "B.SilkS")
			(hide yes)
			(effects
				(font
					(size 1.27 1.27)
				)
				(justify mirror)
			)
		)
		(property "Value" ""
			(at 0 0 90)
			(layer "B.Fab")
			(effects
				(font
					(size 1.27 1.27)
				)
				(justify mirror)
			)
		)
		(duplicate_pad_numbers_are_jumpers no)
		(fp_rect
			(start 0.4953 1.6002)
			(end -0.4953 -0.2032)
			(stroke
				(width 0)
				(type default)
			)
			(fill no)
			(layer "B.CrtYd")
		)
		(fp_line
			(start -0.4953 1.6002)
			(end 0.4953 1.6002)
			(stroke
				(width 0.1)
				(type default)
			)
			(layer "B.Fab")
		)
		(fp_line
			(start 0.4953 1.6002)
			(end 0.4953 -0.2032)
			(stroke
				(width 0.1)
				(type default)
			)
			(layer "B.Fab")
		)
		(fp_line
			(start -0.4953 -0.2032)
			(end -0.4953 1.6002)
			(stroke
				(width 0.1)
				(type default)
			)
			(layer "B.Fab")
		)
		(fp_line
			(start 0.4953 -0.2032)
			(end -0.4953 -0.2032)
			(stroke
				(width 0.1)
				(type default)
			)
			(layer "B.Fab")
		)
		(pad "1" smd rect
			(at 0 0 90)
			(size 0.762 0.889)
			(layers "B.Cu" "B.Mask" "B.Paste")
			(net "PVPP_KLM")
		)
		(pad "2" smd rect
			(at 0 1.397 90)
			(size 0.762 0.889)
			(layers "B.Cu" "B.Mask" "B.Paste")
			(net "GND")
		)
		(zone
			(layer "B.Cu")
			(hatch none 0.5)
			(connect_pads
				(clearance 0)
			)
			(min_thickness 0.25)
			(keepout
				(tracks not_allowed)
				(vias allowed)
				(pads allowed)
				(copperpour not_allowed)
				(footprints allowed)
			)
			(placement
				(enabled no)
				(sheetname "")
			)
			(fill
				(thermal_gap 0.5)
				(thermal_bridge_width 0.5)
				(island_removal_mode 0)
			)
			(polygon
				(pts
					(xy 153.071068 -134.995412) (xy 153.579068 -134.995412) (xy 153.579068 -135.757412) (xy 153.071068 -135.757412)
				)
			)
		)
	)
	(footprint ""
		(layer "B.Cu")
		(at 100.6856 3.8862 -90)
		(property "Reference" "C8U13"
			(at 0 0 90)
			(layer "B.SilkS")
			(hide yes)
			(effects
				(font
					(size 1.27 1.27)
				)
				(justify mirror)
			)
		)
		(property "Value" ""
			(at 0 0 90)
			(layer "B.Fab")
			(effects
				(font
					(size 1.27 1.27)
				)
				(justify mirror)
			)
		)
		(duplicate_pad_numbers_are_jumpers no)
		(fp_rect
			(start 0.500126 1.598422)
			(end -0.500126 -0.201422)
			(stroke
				(width 0)
				(type default)
			)
			(fill no)
			(layer "B.CrtYd")
		)
		(fp_line
			(start -0.500126 1.598422)
			(end 0.500126 1.598422)
			(stroke
				(width 0.1)
				(type default)
			)
			(layer "B.Fab")
		)
		(fp_line
			(start 0.500126 1.598422)
			(end 0.500126 -0.201422)
			(stroke
				(width 0.1)
				(type default)
			)
			(layer "B.Fab")
		)
		(fp_line
			(start -0.500126 -0.201422)
			(end -0.500126 1.598422)
			(stroke
				(width 0.1)
				(type default)
			)
			(layer "B.Fab")
		)
		(fp_line
			(start 0.500126 -0.201422)
			(end -0.500126 -0.201422)
			(stroke
				(width 0.1)
				(type default)
			)
			(layer "B.Fab")
		)
		(pad "1" smd rect
			(at 0 0 180)
			(size 0.889 0.9906)
			(layers "B.Cu" "B.Mask" "B.Paste")
			(net "PVDDQ_GHJ")
		)
		(pad "2" smd rect
			(at 0 1.397 180)
			(size 0.889 0.9906)
			(layers "B.Cu" "B.Mask" "B.Paste")
			(net "GND")
		)
		(zone
			(layer "B.Cu")
			(hatch none 0.5)
			(connect_pads
				(clearance 0)
			)
			(min_thickness 0.25)
			(keepout
				(tracks allowed)
				(vias not_allowed)
				(pads allowed)
				(copperpour not_allowed)
				(footprints allowed)
			)
			(placement
				(enabled no)
				(sheetname "")
			)
			(fill
				(thermal_gap 0.5)
				(thermal_bridge_width 0.5)
				(island_removal_mode 0)
			)
			(polygon
				(pts
					(xy 99.7331 4.3815) (xy 100.2411 4.3815) (xy 100.2411 3.3909) (xy 99.7331 3.3909)
				)
			)
		)
		(zone
			(layer "B.Cu")
			(hatch none 0.5)
			(connect_pads
				(clearance 0)
			)
			(min_thickness 0.25)
			(keepout
				(tracks not_allowed)
				(vias allowed)
				(pads allowed)
				(copperpour not_allowed)
				(footprints allowed)
			)
			(placement
				(enabled no)
				(sheetname "")
			)
			(fill
				(thermal_gap 0.5)
				(thermal_bridge_width 0.5)
				(island_removal_mode 0)
			)
			(polygon
				(pts
					(xy 99.7331 4.3815) (xy 100.2411 4.3815) (xy 100.2411 3.3909) (xy 99.7331 3.3909)
				)
			)
		)
	)
	(footprint ""
		(layer "B.Cu")
		(at 391.668 -87.4395)
		(property "Reference" "R8D19"
			(at 0.8382 -0.67818 0)
			(unlocked yes)
			(layer "B.SilkS")
			(effects
				(font
					(size 0.4064 0.254)
					(thickness 0.1524)
				)
				(justify left mirror)
			)
		)
		(property "Value" ""
			(at 0 0 0)
			(layer "B.Fab")
			(effects
				(font
					(size 1.27 1.27)
				)
				(justify mirror)
			)
		)
		(duplicate_pad_numbers_are_jumpers no)
		(fp_poly
			(pts
				(xy 0.2794 -0.1016) (xy -0.2794 -0.1016) (xy -0.2794 0.9906) (xy 0.2794 0.9906)
			)
			(stroke
				(width 0)
				(type default)
			)
			(fill no)
			(layer "B.CrtYd")
		)
		(fp_line
			(start -0.2794 -0.1016)
			(end 0.2794 -0.1016)
			(stroke
				(width 0.1)
				(type default)
			)
			(layer "B.Fab")
		)
		(fp_line
			(start -0.2794 0.9906)
			(end -0.2794 -0.1016)
			(stroke
				(width 0.1)
				(type default)
			)
			(layer "B.Fab")
		)
		(fp_line
			(start 0.2794 -0.1016)
			(end 0.2794 0.9906)
			(stroke
				(width 0.1)
				(type default)
			)
			(layer "B.Fab")
		)
		(fp_line
			(start 0.2794 0.9906)
			(end -0.2794 0.9906)
			(stroke
				(width 0.1)
				(type default)
			)
			(layer "B.Fab")
		)
		(pad "1" smd rect
			(at 0 0 180)
			(size 0.508 0.508)
			(layers "B.Cu" "B.Mask" "B.Paste")
			(net "SGPIO_PCH_SATA_DOUT0")
		)
		(pad "2" smd rect
			(at 0 0.889 180)
			(size 0.508 0.508)
			(layers "B.Cu" "B.Mask" "B.Paste")
			(net "SGPIO_PCH_SATA_DOUT0_R")
		)
		(zone
			(layer "B.Cu")
			(hatch none 0.5)
			(connect_pads
				(clearance 0)
			)
			(min_thickness 0.25)
			(keepout
				(tracks allowed)
				(vias not_allowed)
				(pads allowed)
				(copperpour not_allowed)
				(footprints allowed)
			)
			(placement
				(enabled no)
				(sheetname "")
			)
			(fill
				(thermal_gap 0.5)
				(thermal_bridge_width 0.5)
				(island_removal_mode 0)
			)
			(polygon
				(pts
					(xy 391.922 -87.1855) (xy 391.414 -87.1855) (xy 391.414 -86.8045) (xy 391.922 -86.8045)
				)
			)
		)
		(zone
			(layer "B.Cu")
			(hatch none 0.5)
			(connect_pads
				(clearance 0)
			)
			(min_thickness 0.25)
			(keepout
				(tracks not_allowed)
				(vias allowed)
				(pads allowed)
				(copperpour not_allowed)
				(footprints allowed)
			)
			(placement
				(enabled no)
				(sheetname "")
			)
			(fill
				(thermal_gap 0.5)
				(thermal_bridge_width 0.5)
				(island_removal_mode 0)
			)
			(polygon
				(pts
					(xy 391.922 -86.8045) (xy 391.414 -86.8045) (xy 391.414 -87.1855) (xy 391.922 -87.1855)
				)
			)
		)
	)
	(footprint ""
		(layer "B.Cu")
		(at 104.775254 -68.17614 180)
		(property "Reference" "C8P33"
			(at 0 0 0)
			(layer "B.SilkS")
			(hide yes)
			(effects
				(font
					(size 1.27 1.27)
				)
				(justify mirror)
			)
		)
		(property "Value" ""
			(at 0 0 0)
			(layer "B.Fab")
			(effects
				(font
					(size 1.27 1.27)
				)
				(justify mirror)
			)
		)
		(duplicate_pad_numbers_are_jumpers no)
		(fp_poly
			(pts
				(xy 0.7239 -0.2159) (xy -0.7239 -0.2159) (xy -0.7239 1.9939) (xy 0.7239 1.9939)
			)
			(stroke
				(width 0)
				(type default)
			)
			(fill no)
			(layer "B.CrtYd")
		)
		(fp_line
			(start 0.7239 1.9939)
			(end -0.7239 1.9939)
			(stroke
				(width 0.1)
				(type default)
			)
			(layer "B.Fab")
		)
		(fp_line
			(start 0.7239 -0.2159)
			(end 0.7239 1.9939)
			(stroke
				(width 0.1)
				(type default)
			)
			(layer "B.Fab")
		)
		(fp_line
			(start -0.7239 1.9939)
			(end -0.7239 -0.2159)
			(stroke
				(width 0.1)
				(type default)
			)
			(layer "B.Fab")
		)
		(fp_line
			(start -0.7239 -0.2159)
			(end 0.7239 -0.2159)
			(stroke
				(width 0.1)
				(type default)
			)
			(layer "B.Fab")
		)
		(pad "1" smd rect
			(at 0 0)
			(size 1.27 1.016)
			(layers "B.Cu" "B.Mask" "B.Paste")
			(net "PVDDQ_GHJ")
		)
		(pad "2" smd rect
			(at 0 1.778)
			(size 1.27 1.016)
			(layers "B.Cu" "B.Mask" "B.Paste")
			(net "GND")
		)
		(zone
			(layer "B.Cu")
			(hatch none 0.5)
			(connect_pads
				(clearance 0)
			)
			(min_thickness 0.25)
			(keepout
				(tracks not_allowed)
				(vias allowed)
				(pads allowed)
				(copperpour not_allowed)
				(footprints allowed)
			)
			(placement
				(enabled no)
				(sheetname "")
			)
			(fill
				(thermal_gap 0.5)
				(thermal_bridge_width 0.5)
				(island_removal_mode 0)
			)
			(polygon
				(pts
					(xy 104.140254 -68.68414) (xy 105.410254 -68.68414) (xy 105.410254 -69.44614) (xy 104.140254 -69.44614)
				)
			)
		)
	)
	(footprint ""
		(layer "B.Cu")
		(at 382.07696 -105.005124 180)
		(property "Reference" "C3N23"
			(at 0 0 0)
			(layer "B.SilkS")
			(hide yes)
			(effects
				(font
					(size 1.27 1.27)
				)
				(justify mirror)
			)
		)
		(property "Value" ""
			(at 0 0 0)
			(layer "B.Fab")
			(effects
				(font
					(size 1.27 1.27)
				)
				(justify mirror)
			)
		)
		(duplicate_pad_numbers_are_jumpers no)
		(fp_rect
			(start 0.2794 0.9144)
			(end -0.2794 -0.1143)
			(stroke
				(width 0)
				(type default)
			)
			(fill no)
			(layer "B.CrtYd")
		)
		(fp_line
			(start 0.2794 0.9144)
			(end 0.2794 -0.1143)
			(stroke
				(width 0.1)
				(type default)
			)
			(layer "B.Fab")
		)
		(fp_line
			(start 0.2794 -0.1143)
			(end -0.2794 -0.1143)
			(stroke
				(width 0.1)
				(type default)
			)
			(layer "B.Fab")
		)
		(fp_line
			(start -0.2794 0.9144)
			(end 0.2794 0.9144)
			(stroke
				(width 0.1)
				(type default)
			)
			(layer "B.Fab")
		)
		(fp_line
			(start -0.2794 -0.1143)
			(end -0.2794 0.9144)
			(stroke
				(width 0.1)
				(type default)
			)
			(layer "B.Fab")
		)
		(pad "1" smd custom
			(at 0 0 90)
			(size 0.10414 0.10414)
			(layers "B.Cu" "B.Mask" "B.Paste")
			(net "P3V3_STBY")
			(options
				(clearance outline)
				(anchor circle)
			)
			(primitives
				(gr_poly
					(pts
						(xy -0.20828 -0.08636) (xy -0.20828 0.08636) (xy -0.08636 0.20828) (xy 0.086614 0.20828) (xy 0.20828 0.086614)
						(xy 0.20828 -0.08636) (xy 0.08636 -0.20828) (xy -0.08636 -0.20828)
					)
					(width 0)
					(fill yes)
				)
			)
		)
		(pad "2" smd custom
			(at 0 0.8001 90)
			(size 0.10414 0.10414)
			(layers "B.Cu" "B.Mask" "B.Paste")
			(net "GND")
			(options
				(clearance outline)
				(anchor circle)
			)
			(primitives
				(gr_poly
					(pts
						(xy -0.20828 -0.08636) (xy -0.20828 0.08636) (xy -0.08636 0.20828) (xy 0.086614 0.20828) (xy 0.20828 0.086614)
						(xy 0.20828 -0.08636) (xy 0.08636 -0.20828) (xy -0.08636 -0.20828)
					)
					(width 0)
					(fill yes)
				)
			)
		)
		(zone
			(layer "B.Cu")
			(hatch none 0.5)
			(connect_pads
				(clearance 0)
			)
			(min_thickness 0.25)
			(keepout
				(tracks not_allowed)
				(vias allowed)
				(pads allowed)
				(copperpour not_allowed)
				(footprints allowed)
			)
			(placement
				(enabled no)
				(sheetname "")
			)
			(fill
				(thermal_gap 0.5)
				(thermal_bridge_width 0.5)
				(island_removal_mode 0)
			)
			(polygon
				(pts
					(xy 381.98933 -105.214674) (xy 381.98933 -105.595674) (xy 382.16459 -105.595674) (xy 382.164844 -105.214674)
				)
			)
		)
		(zone
			(layer "B.Cu")
			(hatch none 0.5)
			(connect_pads
				(clearance 0)
			)
			(min_thickness 0.25)
			(keepout
				(tracks allowed)
				(vias not_allowed)
				(pads allowed)
				(copperpour not_allowed)
				(footprints allowed)
			)
			(placement
				(enabled no)
				(sheetname "")
			)
			(fill
				(thermal_gap 0.5)
				(thermal_bridge_width 0.5)
				(island_removal_mode 0)
			)
			(polygon
				(pts
					(xy 381.98933 -105.214674) (xy 381.98933 -105.595674) (xy 382.16459 -105.595674) (xy 382.164844 -105.214674)
				)
			)
		)
	)
	(footprint ""
		(layer "B.Cu")
		(at 368.935 -104.902 -90)
		(property "Reference" "C3N24"
			(at 0 0 90)
			(layer "B.SilkS")
			(hide yes)
			(effects
				(font
					(size 1.27 1.27)
				)
				(justify mirror)
			)
		)
		(property "Value" ""
			(at 0 0 90)
			(layer "B.Fab")
			(effects
				(font
					(size 1.27 1.27)
				)
				(justify mirror)
			)
		)
		(duplicate_pad_numbers_are_jumpers no)
		(fp_poly
			(pts
				(xy 0.4953 -0.2032) (xy -0.4953 -0.2032) (xy -0.4953 1.6002) (xy 0.4953 1.6002)
			)
			(stroke
				(width 0)
				(type default)
			)
			(fill no)
			(layer "B.CrtYd")
		)
		(fp_line
			(start -0.4953 1.6002)
			(end 0.4953 1.6002)
			(stroke
				(width 0.1)
				(type default)
			)
			(layer "B.Fab")
		)
		(fp_line
			(start 0.4953 1.6002)
			(end 0.4953 -0.2032)
			(stroke
				(width 0.1)
				(type default)
			)
			(layer "B.Fab")
		)
		(fp_line
			(start -0.4953 -0.2032)
			(end -0.4953 1.6002)
			(stroke
				(width 0.1)
				(type default)
			)
			(layer "B.Fab")
		)
		(fp_line
			(start 0.4953 -0.2032)
			(end -0.4953 -0.2032)
			(stroke
				(width 0.1)
				(type default)
			)
			(layer "B.Fab")
		)
		(pad "1" smd rect
			(at 0 0 90)
			(size 0.762 0.889)
			(layers "B.Cu" "B.Mask" "B.Paste")
			(net "PVNN_PCH_STBY")
		)
		(pad "2" smd rect
			(at 0 1.397 90)
			(size 0.762 0.889)
			(layers "B.Cu" "B.Mask" "B.Paste")
			(net "GND")
		)
		(zone
			(layer "B.Cu")
			(hatch none 0.5)
			(connect_pads
				(clearance 0)
			)
			(min_thickness 0.25)
			(keepout
				(tracks not_allowed)
				(vias allowed)
				(pads allowed)
				(copperpour not_allowed)
				(footprints allowed)
			)
			(placement
				(enabled no)
				(sheetname "")
			)
			(fill
				(thermal_gap 0.5)
				(thermal_bridge_width 0.5)
				(island_removal_mode 0)
			)
			(polygon
				(pts
					(xy 368.4905 -104.521) (xy 368.4905 -105.283) (xy 367.9825 -105.283) (xy 367.9825 -104.521)
				)
			)
		)
	)
)
